(kicad_pcb
	(version 20241229)
	(generator "pcbnew")
	(generator_version "9.0")
	(general
		(thickness 1.62)
		(legacy_teardrops no)
	)
	(paper "A4")
	(title_block
		(title "OCuLink to 10GbE adapter")
		(date "2026-02-23")
		(rev "1.1.0")
		(company "Antmicro Ltd")
		(comment 1 "www.antmicro.com")
		(comment 9 "footprints 327-332 of 510")
	)
	(layers
		(0 "F.Cu" signal)
		(4 "In1.Cu" signal)
		(6 "In2.Cu" signal)
		(8 "In3.Cu" signal)
		(10 "In4.Cu" signal)
		(12 "In5.Cu" signal)
		(14 "In6.Cu" signal)
		(2 "B.Cu" signal)
		(9 "F.Adhes" user "F.Adhesive")
		(11 "B.Adhes" user "B.Adhesive")
		(13 "F.Paste" user)
		(15 "B.Paste" user)
		(5 "F.SilkS" user "F.Silkscreen")
		(7 "B.SilkS" user "B.Silkscreen")
		(1 "F.Mask" user)
		(3 "B.Mask" user)
		(17 "Dwgs.User" user "User.Drawings")
		(19 "Cmts.User" user "User.Comments")
		(21 "Eco1.User" user "User.Eco1")
		(23 "Eco2.User" user "User.Eco2")
		(25 "Edge.Cuts" user)
		(27 "Margin" user)
		(31 "F.CrtYd" user "F.Courtyard")
		(29 "B.CrtYd" user "B.Courtyard")
		(35 "F.Fab" user)
		(33 "B.Fab" user)
	)
	(footprint "antmicro-footprints:C_0402_1005Metric"
		(layer "B.Cu")
		(at 107.285001 96.4 -90)
		(descr "Capacitor SMD 0402")
		(tags "capacitor SMD 0402")
		(property "Reference" "C77"
			(at -1.01 0.525001 90)
			(layer "B.SilkS")
			(effects
				(font
					(size 0.7 0.7)
					(thickness 0.15)
				)
				(justify left bottom mirror)
			)
		)
		(property "Value" "C_100n_0402"
			(at -1.022927 -2.155213 90)
			(layer "B.Fab")
			(hide yes)
			(effects
				(font
					(size 0.7 0.7)
					(thickness 0.15)
				)
				(justify left bottom mirror)
			)
		)
		(property "Datasheet" "https://www.murata.com/products/productdetail?partno=GRM155R61H104KE14%23"
			(at 0 0 90)
			(layer "B.Fab")
			(hide yes)
			(effects
				(font
					(size 1.27 1.27)
					(thickness 0.15)
				)
				(justify mirror)
			)
		)
		(property "Description" "SMD Multilayer Ceramic Capacitor, 0.1 µF, 50 V, 0402 [1005 Metric], ± 10%, X5R, GRM Series"
			(at 0 0 90)
			(layer "B.Fab")
			(hide yes)
			(effects
				(font
					(size 1.27 1.27)
					(thickness 0.15)
				)
				(justify mirror)
			)
		)
		(property "MPN" "GRM155R61H104KE14D"
			(at 0 0 270)
			(unlocked yes)
			(layer "B.Fab")
			(hide yes)
			(effects
				(font
					(size 1 1)
					(thickness 0.15)
				)
				(justify mirror)
			)
		)
		(property "Val" "100n"
			(at 0 0 270)
			(unlocked yes)
			(layer "B.Fab")
			(hide yes)
			(effects
				(font
					(size 1 1)
					(thickness 0.15)
				)
				(justify mirror)
			)
		)
		(property "Voltage" "50V"
			(at 0 0 270)
			(unlocked yes)
			(layer "B.Fab")
			(hide yes)
			(effects
				(font
					(size 1 1)
					(thickness 0.15)
				)
				(justify mirror)
			)
		)
		(property "Dielectric" "X5R"
			(at 0 0 270)
			(unlocked yes)
			(layer "B.Fab")
			(hide yes)
			(effects
				(font
					(size 1 1)
					(thickness 0.15)
				)
				(justify mirror)
			)
		)
		(property "Manufacturer" "Murata"
			(at 0 0 270)
			(unlocked yes)
			(layer "B.Fab")
			(hide yes)
			(effects
				(font
					(size 1 1)
					(thickness 0.15)
				)
				(justify mirror)
			)
		)
		(property "License" "Apache-2.0"
			(at 0 0 270)
			(unlocked yes)
			(layer "B.Fab")
			(hide yes)
			(effects
				(font
					(size 1 1)
					(thickness 0.15)
				)
				(justify mirror)
			)
		)
		(property "Author" "Antmicro"
			(at 0 0 270)
			(unlocked yes)
			(layer "B.Fab")
			(hide yes)
			(effects
				(font
					(size 1 1)
					(thickness 0.15)
				)
				(justify mirror)
			)
		)
		(sheetname "/X710-AT2 Misc/")
		(sheetfile "x710-at2-mics.kicad_sch")
		(attr smd)
		(fp_rect
			(start -0.925 0.47)
			(end 0.925 -0.47)
			(stroke
				(width 0.05)
				(type default)
			)
			(fill no)
			(layer "B.CrtYd")
		)
		(fp_line
			(start -0.494 0.25)
			(end 0.504 0.25)
			(stroke
				(width 0.15)
				(type solid)
			)
			(layer "B.Fab")
		)
		(fp_line
			(start 0.504 0.25)
			(end 0.504 -0.248)
			(stroke
				(width 0.15)
				(type solid)
			)
			(layer "B.Fab")
		)
		(fp_line
			(start -0.494 -0.248)
			(end -0.494 0.25)
			(stroke
				(width 0.15)
				(type solid)
			)
			(layer "B.Fab")
		)
		(fp_line
			(start 0.504 -0.248)
			(end -0.494 -0.248)
			(stroke
				(width 0.15)
				(type solid)
			)
			(layer "B.Fab")
		)
		(pad "1" smd roundrect
			(at -0.48 0 270)
			(size 0.59 0.64)
			(layers "B.Cu" "B.Mask" "B.Paste")
			(roundrect_rratio 0.25)
			(net 28 "GND")
			(pintype "passive")
		)
		(pad "2" smd roundrect
			(at 0.48 0 270)
			(size 0.59 0.64)
			(layers "B.Cu" "B.Mask" "B.Paste")
			(roundrect_rratio 0.25)
			(net 7 "+3V3")
			(pintype "passive")
		)
	)
	(footprint "antmicro-footprints:C_1206_3216Metric"
		(layer "B.Cu")
		(at 85 131.45 90)
		(descr "Capacitor SMD 1206")
		(tags "capacitor SMD 1206")
		(property "Reference" "C54"
			(at -4.33 -0.38 90)
			(layer "B.SilkS")
			(effects
				(font
					(size 0.7 0.7)
					(thickness 0.15)
				)
				(justify right top mirror)
			)
		)
		(property "Value" "C_220u_1206_6V3"
			(at 0 -2.101 90)
			(layer "B.Fab")
			(hide yes)
			(effects
				(font
					(size 0.7 0.7)
					(thickness 0.15)
				)
				(justify right top mirror)
			)
		)
		(property "Datasheet" "https://www.murata.com/products/productdetail?partno=GRM31CR60J227ME11%23"
			(at 0 0 90)
			(layer "B.Fab")
			(hide yes)
			(effects
				(font
					(size 1.27 1.27)
					(thickness 0.15)
				)
				(justify mirror)
			)
		)
		(property "Description" "SMD Multilayer Ceramic Capacitor, 220 µF, 6.3 V, 1206 [3216 Metric], ± 20%, X5R, GRM Series"
			(at 0 0 90)
			(layer "B.Fab")
			(hide yes)
			(effects
				(font
					(size 1.27 1.27)
					(thickness 0.15)
				)
				(justify mirror)
			)
		)
		(property "MPN" "GRM31CR60J227ME11L"
			(at 0 0 90)
			(unlocked yes)
			(layer "B.Fab")
			(hide yes)
			(effects
				(font
					(size 1 1)
					(thickness 0.15)
				)
				(justify mirror)
			)
		)
		(property "Manufacturer" "Murata"
			(at 0 0 90)
			(unlocked yes)
			(layer "B.Fab")
			(hide yes)
			(effects
				(font
					(size 1 1)
					(thickness 0.15)
				)
				(justify mirror)
			)
		)
		(property "License" "Apache-2.0"
			(at 0 0 90)
			(unlocked yes)
			(layer "B.Fab")
			(hide yes)
			(effects
				(font
					(size 1 1)
					(thickness 0.15)
				)
				(justify mirror)
			)
		)
		(property "Author" "Antmicro"
			(at 0 0 90)
			(unlocked yes)
			(layer "B.Fab")
			(hide yes)
			(effects
				(font
					(size 1 1)
					(thickness 0.15)
				)
				(justify mirror)
			)
		)
		(property "Val" "220u"
			(at 0 0 90)
			(unlocked yes)
			(layer "B.Fab")
			(hide yes)
			(effects
				(font
					(size 1 1)
					(thickness 0.15)
				)
				(justify mirror)
			)
		)
		(property "Voltage" ""
			(at 0 0 90)
			(unlocked yes)
			(layer "B.Fab")
			(hide yes)
			(effects
				(font
					(size 1 1)
					(thickness 0.15)
				)
				(justify mirror)
			)
		)
		(property "Dielectric" ""
			(at 0 0 90)
			(unlocked yes)
			(layer "B.Fab")
			(hide yes)
			(effects
				(font
					(size 1 1)
					(thickness 0.15)
				)
				(justify mirror)
			)
		)
		(property "Public" "False"
			(at 0 0 90)
			(unlocked yes)
			(layer "B.Fab")
			(hide yes)
			(effects
				(font
					(size 1 1)
					(thickness 0.15)
				)
				(justify mirror)
			)
		)
		(sheetname "/2xRJ45/")
		(sheetfile "2xrj45.kicad_sch")
		(attr smd)
		(fp_line
			(start 0.8 -0.901)
			(end -0.8 -0.901)
			(stroke
				(width 0.15)
				(type solid)
			)
			(layer "B.SilkS")
		)
		(fp_line
			(start 0.8 0.899)
			(end -0.8 0.899)
			(stroke
				(width 0.15)
				(type solid)
			)
			(layer "B.SilkS")
		)
		(fp_rect
			(start -2.325 1.15)
			(end 2.325 -1.15)
			(stroke
				(width 0.05)
				(type default)
			)
			(fill no)
			(layer "B.CrtYd")
		)
		(fp_rect
			(start -1.6 0.799)
			(end 1.6 -0.801)
			(stroke
				(width 0.15)
				(type solid)
			)
			(fill no)
			(layer "B.Fab")
		)
		(pad "1" smd roundrect
			(at -1.5 -0.001 90)
			(size 1.15 1.8)
			(layers "B.Cu" "B.Mask" "B.Paste")
			(roundrect_rratio 0.25)
			(net 28 "GND")
			(pintype "passive")
		)
		(pad "2" smd roundrect
			(at 1.5 -0.001 90)
			(size 1.15 1.8)
			(layers "B.Cu" "B.Mask" "B.Paste")
			(roundrect_rratio 0.25)
			(net 301 "+1V88_CT")
			(pintype "passive")
		)
	)
	(footprint "antmicro-footprints:TP_SMD_0.75mm"
		(layer "B.Cu")
		(at 93.725 107.355 180)
		(property "Reference" "TP25"
			(at -2.395 -1.365 0)
			(layer "B.SilkS")
			(effects
				(font
					(size 0.7 0.7)
					(thickness 0.15)
				)
				(justify left bottom mirror)
			)
		)
		(property "Value" "TP_0.75mm_SMD"
			(at 0 -1.2 0)
			(layer "B.Fab")
			(hide yes)
			(effects
				(font
					(size 0.7 0.7)
					(thickness 0.15)
				)
				(justify left bottom mirror)
			)
		)
		(property "Description" "SMT test point"
			(at 0 0 0)
			(layer "B.Fab")
			(hide yes)
			(effects
				(font
					(size 1.27 1.27)
					(thickness 0.15)
				)
				(justify mirror)
			)
		)
		(property "MPN" ""
			(at 0 0 180)
			(unlocked yes)
			(layer "B.Fab")
			(hide yes)
			(effects
				(font
					(size 1 1)
					(thickness 0.15)
				)
				(justify mirror)
			)
		)
		(property "Manufacturer" ""
			(at 0 0 180)
			(unlocked yes)
			(layer "B.Fab")
			(hide yes)
			(effects
				(font
					(size 1 1)
					(thickness 0.15)
				)
				(justify mirror)
			)
		)
		(property "Author" "Antmicro"
			(at 0 0 180)
			(unlocked yes)
			(layer "B.Fab")
			(hide yes)
			(effects
				(font
					(size 1 1)
					(thickness 0.15)
				)
				(justify mirror)
			)
		)
		(property "License" "Apache-2.0"
			(at 0 0 180)
			(unlocked yes)
			(layer "B.Fab")
			(hide yes)
			(effects
				(font
					(size 1 1)
					(thickness 0.15)
				)
				(justify mirror)
			)
		)
		(sheetname "/X710-AT2 Misc/")
		(sheetfile "x710-at2-mics.kicad_sch")
		(attr exclude_from_pos_files exclude_from_bom)
		(fp_circle
			(center 0 0)
			(end 0.475 0)
			(stroke
				(width 0.05)
				(type default)
			)
			(fill no)
			(layer "B.CrtYd")
		)
		(pad "1" smd circle
			(at 0 0 180)
			(size 0.75 0.75)
			(layers "B.Cu" "B.Mask")
			(net 383 "/X710-AT2 Misc/REFCLK_SEL")
			(pinfunction "1")
			(pintype "passive")
		)
	)
	(footprint "antmicro-footprints:R_0402_1005Metric"
		(layer "B.Cu")
		(at 96.45 102.1)
		(descr "Resistor SMD 0402")
		(tags "resistor SMD 0402")
		(property "Reference" "R60"
			(at 0.9 -0.305556 0)
			(layer "B.SilkS")
			(effects
				(font
					(size 0.7 0.7)
					(thickness 0.15)
				)
				(justify right top mirror)
			)
		)
		(property "Value" "R_3k3_0402"
			(at -1.011843 -1.772046 0)
			(layer "B.Fab")
			(hide yes)
			(effects
				(font
					(size 0.7 0.7)
					(thickness 0.15)
				)
				(justify right top mirror)
			)
		)
		(property "Datasheet" "https://www.bourns.com/docs/product-datasheets/cr.pdf"
			(at 0 0 0)
			(layer "B.Fab")
			(hide yes)
			(effects
				(font
					(size 1.27 1.27)
					(thickness 0.15)
				)
				(justify mirror)
			)
		)
		(property "Description" "SMD Chip Resistor, 3.3 kohm, ± 1%, 63 mW, 0402 [1005 Metric], Thick Film, General Purpose"
			(at 0 0 0)
			(layer "B.Fab")
			(hide yes)
			(effects
				(font
					(size 1.27 1.27)
					(thickness 0.15)
				)
				(justify mirror)
			)
		)
		(property "MPN" "CR0402-FX-3301GLF"
			(at 0 0 0)
			(unlocked yes)
			(layer "B.Fab")
			(hide yes)
			(effects
				(font
					(size 1 1)
					(thickness 0.15)
				)
				(justify mirror)
			)
		)
		(property "Manufacturer" "Bourns"
			(at 0 0 0)
			(unlocked yes)
			(layer "B.Fab")
			(hide yes)
			(effects
				(font
					(size 1 1)
					(thickness 0.15)
				)
				(justify mirror)
			)
		)
		(property "License" "Apache-2.0"
			(at 0 0 0)
			(unlocked yes)
			(layer "B.Fab")
			(hide yes)
			(effects
				(font
					(size 1 1)
					(thickness 0.15)
				)
				(justify mirror)
			)
		)
		(property "Author" "Antmicro"
			(at 0 0 0)
			(unlocked yes)
			(layer "B.Fab")
			(hide yes)
			(effects
				(font
					(size 1 1)
					(thickness 0.15)
				)
				(justify mirror)
			)
		)
		(property "Val" "3k3"
			(at 0 0 0)
			(unlocked yes)
			(layer "B.Fab")
			(hide yes)
			(effects
				(font
					(size 1 1)
					(thickness 0.15)
				)
				(justify mirror)
			)
		)
		(property "Tolerance" "1%"
			(at 0 0 0)
			(unlocked yes)
			(layer "B.Fab")
			(hide yes)
			(effects
				(font
					(size 1 1)
					(thickness 0.15)
				)
				(justify mirror)
			)
		)
		(sheetname "/X710-AT2 10GbE/")
		(sheetfile "x710-at2-10gbe.kicad_sch")
		(attr smd)
		(fp_rect
			(start -0.925 0.47)
			(end 0.925 -0.47)
			(stroke
				(width 0.05)
				(type default)
			)
			(fill no)
			(layer "B.CrtYd")
		)
		(fp_rect
			(start -0.5 0.25)
			(end 0.5 -0.25)
			(stroke
				(width 0.15)
				(type solid)
			)
			(fill no)
			(layer "B.Fab")
		)
		(pad "1" smd roundrect
			(at -0.48 0)
			(size 0.59 0.64)
			(layers "B.Cu" "B.Mask" "B.Paste")
			(roundrect_rratio 0.25)
			(net 95 "/X710-AT2 10GbE/MDIO3_SDA3")
			(pintype "passive")
		)
		(pad "2" smd roundrect
			(at 0.48 0)
			(size 0.59 0.64)
			(layers "B.Cu" "B.Mask" "B.Paste")
			(roundrect_rratio 0.25)
			(net 7 "+3V3")
			(pintype "passive")
		)
	)
	(footprint "antmicro-footprints:C_0402_1005Metric"
		(layer "B.Cu")
		(at 85.225 94.6 90)
		(descr "Capacitor SMD 0402")
		(tags "capacitor SMD 0402")
		(property "Reference" "C96"
			(at 12.5 -0.462343 90)
			(layer "B.SilkS")
			(effects
				(font
					(size 0.7 0.7)
					(thickness 0.15)
				)
				(justify right top mirror)
			)
		)
		(property "Value" "C_1u_25V_0402"
			(at -1.022927 -2.155213 90)
			(layer "B.Fab")
			(hide yes)
			(effects
				(font
					(size 0.7 0.7)
					(thickness 0.15)
				)
				(justify right top mirror)
			)
		)
		(property "Datasheet" "https://www.murata.com/products/productdetail?partno=GRM155R61E105KE11%23"
			(at 0 0 90)
			(layer "B.Fab")
			(hide yes)
			(effects
				(font
					(size 1.27 1.27)
					(thickness 0.15)
				)
				(justify mirror)
			)
		)
		(property "Description" "SMD Multilayer Ceramic Capacitor, 1 µF, 25 V, 0402 [1005 Metric], ± 10%, X5R, GRM Series"
			(at 0 0 90)
			(layer "B.Fab")
			(hide yes)
			(effects
				(font
					(size 1.27 1.27)
					(thickness 0.15)
				)
				(justify mirror)
			)
		)
		(property "MPN" "GRM155R61E105KE11J"
			(at 0 0 90)
			(unlocked yes)
			(layer "B.Fab")
			(hide yes)
			(effects
				(font
					(size 1 1)
					(thickness 0.15)
				)
				(justify mirror)
			)
		)
		(property "Manufacturer" "Murata"
			(at 0 0 90)
			(unlocked yes)
			(layer "B.Fab")
			(hide yes)
			(effects
				(font
					(size 1 1)
					(thickness 0.15)
				)
				(justify mirror)
			)
		)
		(property "License" "Apache-2.0"
			(at 0 0 90)
			(unlocked yes)
			(layer "B.Fab")
			(hide yes)
			(effects
				(font
					(size 1 1)
					(thickness 0.15)
				)
				(justify mirror)
			)
		)
		(property "Author" "Antmicro"
			(at 0 0 90)
			(unlocked yes)
			(layer "B.Fab")
			(hide yes)
			(effects
				(font
					(size 1 1)
					(thickness 0.15)
				)
				(justify mirror)
			)
		)
		(property "Val" "1u"
			(at 0 0 90)
			(unlocked yes)
			(layer "B.Fab")
			(hide yes)
			(effects
				(font
					(size 1 1)
					(thickness 0.15)
				)
				(justify mirror)
			)
		)
		(property "Voltage" "25V"
			(at 0 0 90)
			(unlocked yes)
			(layer "B.Fab")
			(hide yes)
			(effects
				(font
					(size 1 1)
					(thickness 0.15)
				)
				(justify mirror)
			)
		)
		(property "Dielectric" "X5R"
			(at 0 0 90)
			(unlocked yes)
			(layer "B.Fab")
			(hide yes)
			(effects
				(font
					(size 1 1)
					(thickness 0.15)
				)
				(justify mirror)
			)
		)
		(sheetname "/X710-AT2 power/")
		(sheetfile "x710-at2-power.kicad_sch")
		(attr smd)
		(fp_rect
			(start -0.925 0.47)
			(end 0.925 -0.47)
			(stroke
				(width 0.05)
				(type default)
			)
			(fill no)
			(layer "B.CrtYd")
		)
		(fp_line
			(start 0.504 -0.248)
			(end -0.494 -0.248)
			(stroke
				(width 0.15)
				(type solid)
			)
			(layer "B.Fab")
		)
		(fp_line
			(start -0.494 -0.248)
			(end -0.494 0.25)
			(stroke
				(width 0.15)
				(type solid)
			)
			(layer "B.Fab")
		)
		(fp_line
			(start 0.504 0.25)
			(end 0.504 -0.248)
			(stroke
				(width 0.15)
				(type solid)
			)
			(layer "B.Fab")
		)
		(fp_line
			(start -0.494 0.25)
			(end 0.504 0.25)
			(stroke
				(width 0.15)
				(type solid)
			)
			(layer "B.Fab")
		)
		(pad "1" smd roundrect
			(at -0.48 0 90)
			(size 0.59 0.64)
			(layers "B.Cu" "B.Mask" "B.Paste")
			(roundrect_rratio 0.25)
			(net 28 "GND")
			(pintype "passive")
		)
		(pad "2" smd roundrect
			(at 0.48 0 90)
			(size 0.59 0.64)
			(layers "B.Cu" "B.Mask" "B.Paste")
			(roundrect_rratio 0.25)
			(net 1 "VCCA")
			(pintype "passive")
		)
	)
	(footprint "antmicro-footprints:R_0402_1005Metric"
		(layer "B.Cu")
		(at 84.25 102 90)
		(descr "Resistor SMD 0402")
		(tags "resistor SMD 0402")
		(property "Reference" "R143"
			(at 9.09 -0.447343 90)
			(layer "B.SilkS")
			(effects
				(font
					(size 0.7 0.7)
					(thickness 0.15)
				)
				(justify right top mirror)
			)
		)
		(property "Value" "R_1k_0402"
			(at -1.011843 -1.772046 90)
			(layer "B.Fab")
			(hide yes)
			(effects
				(font
					(size 0.7 0.7)
					(thickness 0.15)
				)
				(justify right top mirror)
			)
		)
		(property "Datasheet" "https://www.bourns.com/docs/product-datasheets/cr.pdf"
			(at 0 0 90)
			(layer "B.Fab")
			(hide yes)
			(effects
				(font
					(size 1.27 1.27)
					(thickness 0.15)
				)
				(justify mirror)
			)
		)
		(property "Description" "SMD Chip Resistor, 1 kohm, ± 1%, 63 mW, 0402 [1005 Metric], Thick Film, General Purpose"
			(at 0 0 90)
			(layer "B.Fab")
			(hide yes)
			(effects
				(font
					(size 1.27 1.27)
					(thickness 0.15)
				)
				(justify mirror)
			)
		)
		(property "MPN" "CR0402-FX-1001GLF"
			(at 0 0 90)
			(unlocked yes)
			(layer "B.Fab")
			(hide yes)
			(effects
				(font
					(size 1 1)
					(thickness 0.15)
				)
				(justify mirror)
			)
		)
		(property "Manufacturer" "Bourns"
			(at 0 0 90)
			(unlocked yes)
			(layer "B.Fab")
			(hide yes)
			(effects
				(font
					(size 1 1)
					(thickness 0.15)
				)
				(justify mirror)
			)
		)
		(property "License" "Apache-2.0"
			(at 0 0 90)
			(unlocked yes)
			(layer "B.Fab")
			(hide yes)
			(effects
				(font
					(size 1 1)
					(thickness 0.15)
				)
				(justify mirror)
			)
		)
		(property "Author" "Antmicro"
			(at 0 0 90)
			(unlocked yes)
			(layer "B.Fab")
			(hide yes)
			(effects
				(font
					(size 1 1)
					(thickness 0.15)
				)
				(justify mirror)
			)
		)
		(property "Val" "1k"
			(at 0 0 90)
			(unlocked yes)
			(layer "B.Fab")
			(hide yes)
			(effects
				(font
					(size 1 1)
					(thickness 0.15)
				)
				(justify mirror)
			)
		)
		(property "Tolerance" "1%"
			(at 0 0 90)
			(unlocked yes)
			(layer "B.Fab")
			(hide yes)
			(effects
				(font
					(size 1 1)
					(thickness 0.15)
				)
				(justify mirror)
			)
		)
		(sheetname "/X710-AT2 RSVD/")
		(sheetfile "x710-at2-rsvd.kicad_sch")
		(attr smd)
		(fp_rect
			(start -0.925 0.47)
			(end 0.925 -0.47)
			(stroke
				(width 0.05)
				(type default)
			)
			(fill no)
			(layer "B.CrtYd")
		)
		(fp_rect
			(start -0.5 0.25)
			(end 0.5 -0.25)
			(stroke
				(width 0.15)
				(type solid)
			)
			(fill no)
			(layer "B.Fab")
		)
		(pad "1" smd roundrect
			(at -0.48 0 90)
			(size 0.59 0.64)
			(layers "B.Cu" "B.Mask" "B.Paste")
			(roundrect_rratio 0.25)
			(net 292 "/X710-AT2 RSVD/RSVDE19_1P88V")
			(pintype "passive")
		)
		(pad "2" smd roundrect
			(at 0.48 0 90)
			(size 0.59 0.64)
			(layers "B.Cu" "B.Mask" "B.Paste")
			(roundrect_rratio 0.25)
			(net 18 "+1V88")
			(pintype "passive")
		)
	)
)
